# S9S_MB_2U (Grand Teton) — schematic netlist excerpt (pin names and nets, part order shuffled) for the footprints in the layout excerpt that follows; sources: Cadence DE-HDL packaged netlist, KiCad conversion of 03242023_DA0F0TMBIJ0_F0T_Motherboard_J_brd_V01_OCP.brd

R69  Q_RES  10K 1% CHIP  pkg 0402LF  page 43 : A = PWRGD_PLT_AUX_CPU0_LVT3 ; B = GND
C1946  Q_CAP  0.1UF 25V 10% X7R  pkg 0402  page 217 : A = P3V3_AUX_FPGA_VCCIO1 ; B = GND

(kicad_pcb
	(version 20260206)
	(generator "pcbnew")
	(generator_version "10.0")
	(general
		(thickness 1.6)
		(legacy_teardrops no)
	)
	(paper "A4")
	(title_block
		(title "03242023_DA0F0TMBIJ0_F0T_Motherboard_J_brd_V01_OCP.brd")
		(comment 1 "Grand Teton / footprints 4315-4316 of 6105")
	)
	(layers
		(0 "F.Cu" signal "TOP")
		(4 "In1.Cu" signal "GND")
		(6 "In2.Cu" signal "IN1")
		(8 "In3.Cu" signal "GND1")
		(10 "In4.Cu" signal "IN2")
		(12 "In5.Cu" signal "GND2")
		(14 "In6.Cu" signal "IN3")
		(16 "In7.Cu" signal "GND3")
		(18 "In8.Cu" signal "VCC")
		(20 "In9.Cu" signal "VCC1")
		(22 "In10.Cu" signal "GND4")
		(24 "In11.Cu" signal "IN4")
		(26 "In12.Cu" signal "GND5")
		(28 "In13.Cu" signal "IN5")
		(30 "In14.Cu" signal "GND6")
		(32 "In15.Cu" signal "IN6")
		(34 "In16.Cu" signal "GND7")
		(2 "B.Cu" signal "BOTTOM")
		(9 "F.Adhes" user "F.Adhesive")
		(11 "B.Adhes" user "B.Adhesive")
		(13 "F.Paste" user "Package Geometry/Pastemask Top")
		(15 "B.Paste" user "Package Geometry/Pastemask Bottom")
		(5 "F.SilkS" user "Ref Des/Silkscreen Top")
		(7 "B.SilkS" user "Ref Des/Silkscreen Bottom")
		(1 "F.Mask" user "Board Geometry/Soldermask Top")
		(3 "B.Mask" user "Board Geometry/Soldermask Bottom")
		(17 "Dwgs.User" user "User.Drawings")
		(19 "Cmts.User" user "User.Comments")
		(21 "Eco1.User" user "User.Eco1")
		(23 "Eco2.User" user "User.Eco2")
		(25 "Edge.Cuts" user "Board Geometry/Outline")
		(27 "Margin" user)
		(31 "F.CrtYd" user "Package Geometry/Place Bound Top")
		(29 "B.CrtYd" user "Package Geometry/Place Bound Bottom")
		(35 "F.Fab" user "Ref Des/Assembly Top")
		(33 "B.Fab" user "Ref Des/Assembly Bottom")
	)
	(footprint ""
		(layer "B.Cu")
		(at 176.45888 -123.948698 -90)
		(property "Reference" "C1946"
			(at 0 0 90)
			(layer "B.SilkS")
			(hide yes)
			(effects
				(font
					(size 1.27 1.27)
				)
				(justify mirror)
			)
		)
		(property "Value" ""
			(at 0 0 90)
			(layer "B.Fab")
			(effects
				(font
					(size 1.27 1.27)
				)
				(justify mirror)
			)
		)
		(duplicate_pad_numbers_are_jumpers no)
		(fp_line
			(start -0.7874 0.4064)
			(end 0.7874 0.4064)
			(stroke
				(width 0.1524)
				(type default)
			)
			(layer "B.SilkS")
		)
		(fp_line
			(start 0.7874 0.4064)
			(end 0.7874 -0.4064)
			(stroke
				(width 0.1524)
				(type default)
			)
			(layer "B.SilkS")
		)
		(fp_line
			(start -0.7874 -0.4064)
			(end -0.7874 0.4064)
			(stroke
				(width 0.1524)
				(type default)
			)
			(layer "B.SilkS")
		)
		(fp_line
			(start 0.7874 -0.4064)
			(end -0.7874 -0.4064)
			(stroke
				(width 0.1524)
				(type default)
			)
			(layer "B.SilkS")
		)
		(fp_line
			(start -0.67945 0.3048)
			(end -0.120396 0.3048)
			(stroke
				(width 0.1)
				(type default)
			)
			(layer "B.Fab")
		)
		(fp_line
			(start -0.120396 0.3048)
			(end -0.120396 0.2794)
			(stroke
				(width 0.1)
				(type default)
			)
			(layer "B.Fab")
		)
		(fp_line
			(start 0.12065 0.3048)
			(end 0.67945 0.3048)
			(stroke
				(width 0.1)
				(type default)
			)
			(layer "B.Fab")
		)
		(fp_line
			(start 0.67945 0.3048)
			(end 0.67945 -0.305054)
			(stroke
				(width 0.1)
				(type default)
			)
			(layer "B.Fab")
		)
		(fp_line
			(start -0.120396 0.2794)
			(end 0.12065 0.2794)
			(stroke
				(width 0.1)
				(type default)
			)
			(layer "B.Fab")
		)
		(fp_line
			(start 0.12065 0.2794)
			(end 0.12065 0.3048)
			(stroke
				(width 0.1)
				(type default)
			)
			(layer "B.Fab")
		)
		(fp_line
			(start -0.12065 -0.2794)
			(end -0.12065 -0.3048)
			(stroke
				(width 0.1)
				(type default)
			)
			(layer "B.Fab")
		)
		(fp_line
			(start 0.12065 -0.2794)
			(end -0.12065 -0.2794)
			(stroke
				(width 0.1)
				(type default)
			)
			(layer "B.Fab")
		)
		(fp_line
			(start -0.67945 -0.3048)
			(end -0.67945 0.3048)
			(stroke
				(width 0.1)
				(type default)
			)
			(layer "B.Fab")
		)
		(fp_line
			(start -0.12065 -0.3048)
			(end -0.67945 -0.3048)
			(stroke
				(width 0.1)
				(type default)
			)
			(layer "B.Fab")
		)
		(fp_line
			(start 0.12065 -0.305054)
			(end 0.12065 -0.2794)
			(stroke
				(width 0.1)
				(type default)
			)
			(layer "B.Fab")
		)
		(fp_line
			(start 0.67945 -0.305054)
			(end 0.12065 -0.305054)
			(stroke
				(width 0.1)
				(type default)
			)
			(layer "B.Fab")
		)
		(pad "1" smd circle
			(at 0.40005 0 90)
			(size 0 0)
			(layers "B.Cu" "B.Mask" "B.Paste")
			(net "P3V3_AUX_FPGA_VCCIO1")
		)
		(pad "2" smd circle
			(at -0.40005 0 90)
			(size 0 0)
			(layers "B.Cu" "B.Mask" "B.Paste")
			(net "GND")
		)
	)
	(footprint ""
		(layer "B.Cu")
		(at 385.46405 -190.82131 90)
		(property "Reference" "R69"
			(at 0 0 90)
			(layer "B.SilkS")
			(hide yes)
			(effects
				(font
					(size 1.27 1.27)
				)
				(justify mirror)
			)
		)
		(property "Value" ""
			(at 0 0 90)
			(layer "B.Fab")
			(effects
				(font
					(size 1.27 1.27)
				)
				(justify mirror)
			)
		)
		(duplicate_pad_numbers_are_jumpers no)
		(fp_line
			(start 0.7874 -0.4064)
			(end -0.7874 -0.4064)
			(stroke
				(width 0.1524)
				(type default)
			)
			(layer "B.SilkS")
		)
		(fp_line
			(start -0.7874 -0.4064)
			(end -0.7874 0.4064)
			(stroke
				(width 0.1524)
				(type default)
			)
			(layer "B.SilkS")
		)
		(fp_line
			(start 0.7874 0.4064)
			(end 0.7874 -0.4064)
			(stroke
				(width 0.1524)
				(type default)
			)
			(layer "B.SilkS")
		)
		(fp_line
			(start -0.7874 0.4064)
			(end 0.7874 0.4064)
			(stroke
				(width 0.1524)
				(type default)
			)
			(layer "B.SilkS")
		)
		(fp_line
			(start 0.67945 -0.305054)
			(end 0.12065 -0.305054)
			(stroke
				(width 0.1)
				(type default)
			)
			(layer "B.Fab")
		)
		(fp_line
			(start 0.12065 -0.305054)
			(end 0.12065 -0.2794)
			(stroke
				(width 0.1)
				(type default)
			)
			(layer "B.Fab")
		)
		(fp_line
			(start -0.12065 -0.3048)
			(end -0.67945 -0.3048)
			(stroke
				(width 0.1)
				(type default)
			)
			(layer "B.Fab")
		)
		(fp_line
			(start -0.67945 -0.3048)
			(end -0.67945 0.3048)
			(stroke
				(width 0.1)
				(type default)
			)
			(layer "B.Fab")
		)
		(fp_line
			(start 0.12065 -0.2794)
			(end -0.12065 -0.2794)
			(stroke
				(width 0.1)
				(type default)
			)
			(layer "B.Fab")
		)
		(fp_line
			(start -0.12065 -0.2794)
			(end -0.12065 -0.3048)
			(stroke
				(width 0.1)
				(type default)
			)
			(layer "B.Fab")
		)
		(fp_line
			(start 0.12065 0.2794)
			(end 0.12065 0.3048)
			(stroke
				(width 0.1)
				(type default)
			)
			(layer "B.Fab")
		)
		(fp_line
			(start -0.120396 0.2794)
			(end 0.12065 0.2794)
			(stroke
				(width 0.1)
				(type default)
			)
			(layer "B.Fab")
		)
		(fp_line
			(start 0.67945 0.3048)
			(end 0.67945 -0.305054)
			(stroke
				(width 0.1)
				(type default)
			)
			(layer "B.Fab")
		)
		(fp_line
			(start 0.12065 0.3048)
			(end 0.67945 0.3048)
			(stroke
				(width 0.1)
				(type default)
			)
			(layer "B.Fab")
		)
		(fp_line
			(start -0.120396 0.3048)
			(end -0.120396 0.2794)
			(stroke
				(width 0.1)
				(type default)
			)
			(layer "B.Fab")
		)
		(fp_line
			(start -0.67945 0.3048)
			(end -0.120396 0.3048)
			(stroke
				(width 0.1)
				(type default)
			)
			(layer "B.Fab")
		)
		(pad "1" smd circle
			(at 0.40005 0 270)
			(size 0 0)
			(layers "B.Cu" "B.Mask" "B.Paste")
			(net "PWRGD_PLT_AUX_CPU0_LVT3")
		)
		(pad "2" smd circle
			(at -0.40005 0 270)
			(size 0 0)
			(layers "B.Cu" "B.Mask" "B.Paste")
			(net "GND")
		)
	)
)
